FILE_TYPE = MACRO_DRAWING;
SET COLOR_WIRE YELLOW;
SET COLOR_PROP ORANGE;
SET COLOR_DOT WHITE;
SET COLOR_ARC YELLOW;
SET COLOR_BODY GREEN;
SET COLOR_NOTE PURPLE;
SET PROP_DISPLAY VALUE;
SET PAGE_NUMBER P40;
SET PATH_NUMBER P3;
FORCEADD LCMXO3LF2100C5BG256C..7
(-4750 4425);
FORCEPROP 1 LAST PART_NUMBER AJ021000T03
J 0
(-5193 5221);
DISPLAY 0.723404 (-5193 5221);
PAINT GREEN (-5193 5221);
FORCEPROP 1 LAST MATERIAL IC
J 0
(-5193 5130);
DISPLAY 0.723404 (-5193 5130);
PAINT GREEN (-5193 5130);
FORCEPROP 2 LAST PART_TYPE SMLF
J 0
(-5175 5425);
DISPLAY 0.680851 (-5175 5425);
FORCEPROP 2 LAST VALUE LCMXO3LF-2100C-5BG256C
J 0
(-5175 5375);
DISPLAY 0.680851 (-5175 5375);
FORCEPROP 2 LAST CDS_LIB pure_quanta
J 0
(-4750 4425);
DISPLAY INVISIBLE (-4750 4425);
FORCEPROP 1 LAST PATH I1
J 0
(-4750 4425);
DISPLAY 0.723404 (-4750 4425);
PAINT GREEN (-4750 4425);
DISPLAY INVISIBLE (-4750 4425);
FORCEPROP 1 LAST NEEDS_NO_SIZE TRUE
J 0
(-4750 4425);
DISPLAY 0.723404 (-4750 4425);
PAINT GREEN (-4750 4425);
DISPLAY INVISIBLE (-4750 4425);
FORCEPROP 1 LAST CDS_LMAN_SYM_OUTLINE -450,700,450,-700
J 0
(-4750 4425);
DISPLAY 0.468085 (-4750 4425);
PAINT GREEN (-4750 4425);
DISPLAY INVISIBLE (-4750 4425);
FORCEPROP 1 LAST LOCATION U25
J 0
(-5193 5320);
DISPLAY 0.723404 (-5193 5320);
PAINT GREEN (-5193 5320);
FORCEPROP 0 LASTPIN (-5350 5025) $PN B2
J 2
(-5360 5035);
DISPLAY 0.680851 (-5360 5035);
PAINT MONO (-5360 5035);
FORCEPROP 0 LASTPIN (-5350 4975) $PN B15
J 2
(-5360 4985);
DISPLAY 0.680851 (-5360 4985);
PAINT MONO (-5360 4985);
FORCEPROP 0 LASTPIN (-5350 4925) $PN C3
J 2
(-5360 4935);
DISPLAY 0.680851 (-5360 4935);
PAINT MONO (-5360 4935);
FORCEPROP 0 LASTPIN (-5350 4875) $PN C14
J 2
(-5360 4885);
DISPLAY 0.680851 (-5360 4885);
PAINT MONO (-5360 4885);
FORCEPROP 0 LASTPIN (-5350 4825) $PN D4
J 2
(-5360 4835);
DISPLAY 0.680851 (-5360 4835);
PAINT MONO (-5360 4835);
FORCEPROP 0 LASTPIN (-5350 4775) $PN D13
J 2
(-5360 4785);
DISPLAY 0.680851 (-5360 4785);
PAINT MONO (-5360 4785);
FORCEPROP 0 LASTPIN (-5350 4725) $PN E5
J 2
(-5360 4735);
DISPLAY 0.680851 (-5360 4735);
PAINT MONO (-5360 4735);
FORCEPROP 0 LASTPIN (-5350 4675) $PN E12
J 2
(-5360 4685);
DISPLAY 0.680851 (-5360 4685);
PAINT MONO (-5360 4685);
FORCEPROP 0 LASTPIN (-5350 4625) $PN F6
J 2
(-5360 4635);
DISPLAY 0.680851 (-5360 4635);
PAINT MONO (-5360 4635);
FORCEPROP 0 LASTPIN (-5350 4575) $PN F11
J 2
(-5360 4585);
DISPLAY 0.680851 (-5360 4585);
PAINT MONO (-5360 4585);
FORCEPROP 0 LASTPIN (-5350 4525) $PN H8
J 2
(-5360 4535);
DISPLAY 0.680851 (-5360 4535);
PAINT MONO (-5360 4535);
FORCEPROP 0 LASTPIN (-5350 4475) $PN H9
J 2
(-5360 4485);
DISPLAY 0.680851 (-5360 4485);
PAINT MONO (-5360 4485);
FORCEPROP 0 LASTPIN (-5350 4425) $PN J8
J 2
(-5360 4435);
DISPLAY 0.680851 (-5360 4435);
PAINT MONO (-5360 4435);
FORCEPROP 0 LASTPIN (-5350 4375) $PN J9
J 2
(-5360 4385);
DISPLAY 0.680851 (-5360 4385);
PAINT MONO (-5360 4385);
FORCEPROP 0 LASTPIN (-5350 4325) $PN L6
J 2
(-5360 4335);
DISPLAY 0.680851 (-5360 4335);
PAINT MONO (-5360 4335);
FORCEPROP 0 LASTPIN (-5350 4275) $PN L11
J 2
(-5360 4285);
DISPLAY 0.680851 (-5360 4285);
PAINT MONO (-5360 4285);
FORCEPROP 0 LASTPIN (-5350 4225) $PN M5
J 2
(-5360 4235);
DISPLAY 0.680851 (-5360 4235);
PAINT MONO (-5360 4235);
FORCEPROP 0 LASTPIN (-5350 4175) $PN M12
J 2
(-5360 4185);
DISPLAY 0.680851 (-5360 4185);
PAINT MONO (-5360 4185);
FORCEPROP 0 LASTPIN (-5350 4125) $PN N4
J 2
(-5360 4135);
DISPLAY 0.680851 (-5360 4135);
PAINT MONO (-5360 4135);
FORCEPROP 0 LASTPIN (-5350 4075) $PN N13
J 2
(-5360 4085);
DISPLAY 0.680851 (-5360 4085);
PAINT MONO (-5360 4085);
FORCEPROP 0 LASTPIN (-5350 4025) $PN P3
J 2
(-5360 4035);
DISPLAY 0.680851 (-5360 4035);
PAINT MONO (-5360 4035);
FORCEPROP 0 LASTPIN (-5350 3975) $PN P14
J 2
(-5360 3985);
DISPLAY 0.680851 (-5360 3985);
PAINT MONO (-5360 3985);
FORCEPROP 0 LASTPIN (-5350 3925) $PN R2
J 2
(-5360 3935);
DISPLAY 0.680851 (-5360 3935);
PAINT MONO (-5360 3935);
FORCEPROP 0 LASTPIN (-5350 3875) $PN R15
J 2
(-5360 3885);
DISPLAY 0.680851 (-5360 3885);
PAINT MONO (-5360 3885);
FORCEPROP 0 LASTPIN (-4150 4475) $PN A2
J 0
(-4140 4485);
DISPLAY 0.680851 (-4140 4485);
PAINT MONO (-4140 4485);
FORCEPROP 0 LASTPIN (-4150 5025) $PN A1
J 0
(-4140 5035);
DISPLAY 0.680851 (-4140 5035);
PAINT MONO (-4140 5035);
FORCEPROP 0 LASTPIN (-4150 4975) $PN A16
J 0
(-4140 4985);
DISPLAY 0.680851 (-4140 4985);
PAINT MONO (-4140 4985);
FORCEPROP 0 LASTPIN (-4150 4925) $PN G7
J 0
(-4140 4935);
DISPLAY 0.680851 (-4140 4935);
PAINT MONO (-4140 4935);
FORCEPROP 0 LASTPIN (-4150 4875) $PN G10
J 0
(-4140 4885);
DISPLAY 0.680851 (-4140 4885);
PAINT MONO (-4140 4885);
FORCEPROP 0 LASTPIN (-4150 4825) $PN K7
J 0
(-4140 4835);
DISPLAY 0.680851 (-4140 4835);
PAINT MONO (-4140 4835);
FORCEPROP 0 LASTPIN (-4150 4775) $PN K10
J 0
(-4140 4785);
DISPLAY 0.680851 (-4140 4785);
PAINT MONO (-4140 4785);
FORCEPROP 0 LASTPIN (-4150 4725) $PN T1
J 0
(-4140 4735);
DISPLAY 0.680851 (-4140 4735);
PAINT MONO (-4140 4735);
FORCEPROP 0 LASTPIN (-4150 4675) $PN T16
J 0
(-4140 4685);
DISPLAY 0.680851 (-4140 4685);
PAINT MONO (-4140 4685);
FORCEPROP 0 LAST $SEC 7
J 0
(-5175 5475);
DISPLAY 0.680851 (-5175 5475);
PAINT MONO (-5175 5475);
DISPLAY INVISIBLE (-5175 5475);
FORCEPROP 0 LAST CDS_SEC 7
J 0
(-5175 5475);
DISPLAY 0.680851 (-5175 5475);
DISPLAY INVISIBLE (-5175 5475);
FORCEADD UNIVERSAL_GND..1
(-5550 3300);
FORCEPROP 3 LASTPIN (-5550 3350) SIG_NAME GND\g
J 0
(-5540 3360);
DISPLAY 0.659574 (-5540 3360);
PAINT MONO (-5540 3360);
DISPLAY INVISIBLE (-5540 3360);
FORCEPROP 1 LAST HDL_POWER GND
J 1
(-5525 3225);
DISPLAY 0.702128 (-5525 3225);
PAINT GREEN (-5525 3225);
DISPLAY INVISIBLE (-5525 3225);
FORCEPROP 1 LAST PATH I2
J 0
(-5475 3300);
DISPLAY 0.872340 (-5475 3300);
PAINT AQUA (-5475 3300);
DISPLAY INVISIBLE (-5475 3300);
FORCEPROP 2 LAST CDS_LIB logical_power
J 0
(-5550 3300);
DISPLAY INVISIBLE (-5550 3300);
FORCEADD UNIVERSAL_POWER..1
(-3950 5275);
FORCEPROP 3 LASTPIN (-3950 5225) SIG_NAME PVCCA_AUX_PLD\g
J 0
(-3940 5235);
DISPLAY 0.659574 (-3940 5235);
PAINT MONO (-3940 5235);
DISPLAY INVISIBLE (-3940 5235);
FORCEPROP 1 LAST HDL_POWER PVCCA_AUX_PLD
J 1
(-3950 5325);
DISPLAY 0.702128 (-3950 5325);
PAINT GREEN (-3950 5325);
FORCEPROP 1 LAST PATH I3
J 0
(-3900 5300);
DISPLAY 0.872340 (-3900 5300);
PAINT AQUA (-3900 5300);
DISPLAY INVISIBLE (-3900 5300);
FORCEPROP 2 LAST CDS_LIB logical_power
J 0
(-3950 5275);
DISPLAY INVISIBLE (-3950 5275);
FORCEADD QUANTA_TITLE_BLOCK_C..1
(0 0);
FORCEPROP 0 LAST CDS_CON_LAST_MODIFIED Fri Aug 25 17:25:45 2023
J 0
(-1885 15);
DISPLAY INVISIBLE (-1885 15);
FORCEPROP 2 LAST Q_DEPT 
J 1
(-3763 49);
DISPLAY 1.957447 (-3763 49);
PAINT GREEN (-3763 49);
FORCEPROP 1 LAST CUSTOM_TXT_CDS <CON_LAST_MODIFIED>
J 0
(-1885 15);
DISPLAY 0.978723 (-1885 15);
FORCEPROP 2 LAST CUSTOM_TXT_CDS <XR_PAGE_TITLE>
J 0
(-7890 5250);
DISPLAY 0.638298 (-7890 5250);
PAINT PINK (-7890 5250);
DISPLAY INVISIBLE (-7890 5250);
FORCEPROP 1 LAST CUSTOM_TXT_CDS <NAME_2>
J 0
(-3175 50);
FORCEPROP 1 LAST CUSTOM_TXT_CDS <NAME_1>
J 0
(-3175 175);
FORCEPROP 1 LAST CUSTOM_TXT_CDS <Q_NUMBER>
J 0
(-1403 103);
DISPLAY 1.212766 (-1403 103);
FORCEPROP 1 LAST CUSTOM_TXT_CDS <Q_PROJ>
J 0
(-2382 102);
DISPLAY 1.212766 (-2382 102);
FORCEPROP 1 LAST CUSTOM_TXT_CDS <Q_REV>
J 0
(-184 103);
DISPLAY 1.212766 (-184 103);
FORCEPROP 1 LAST CUSTOM_TXT_CDS <CON_PAGE_NUM> OF <CON_TOTAL_PAGES>
J 0
(-446 18);
DISPLAY 0.978723 (-446 18);
FORCEPROP 1 LAST Q_TITLE FPGA 7/8
J 0
(-9366 26);
DISPLAY 2.446809 (-9366 26);
PAINT GREEN (-9366 26);
FORCEPROP 1 LAST CDS_LMAN_SYM_OUTLINE -9475,6775,100,-125
J 0
(0 0);
DISPLAY 0.468085 (0 0);
PAINT GREEN (0 0);
DISPLAY INVISIBLE (0 0);
FORCEPROP 1 LAST COMMENT_BODY TRUE
J 0
(12 -13);
DISPLAY 0.978723 (12 -13);
PAINT GREEN (12 -13);
DISPLAY INVISIBLE (12 -13);
FORCEPROP 2 LAST CDS_LIB pure_quanta
J 0
(0 0);
DISPLAY INVISIBLE (0 0);
FORCEPROP 2 LAST PAGE_BORDER TRUE
J 0
(-7890 5250);
DISPLAY 0.638298 (-7890 5250);
PAINT PINK (-7890 5250);
DISPLAY INVISIBLE (-7890 5250);
FORCEPROP 2 LAST CDS_XR_PAGE_TITLE CR-40 : @SCM_LIB.SCM(SCH_1):PAGE40
J 0
(-7890 5250);
DISPLAY 0.638298 (-7890 5250);
PAINT PINK (-7890 5250);
DISPLAY INVISIBLE (-7890 5250);
WIRE 16 -1 (-3950 5225)(-3950 5025);
WIRE 16 -1 (-5550 3350)(-5550 3875);
WIRE 16 -1 (-5550 3875)(-5350 3875);
WIRE 16 -1 (-5550 3875)(-5550 3925);
WIRE 16 -1 (-5550 3925)(-5350 3925);
WIRE 16 -1 (-5550 3925)(-5550 3975);
WIRE 16 -1 (-5550 3975)(-5350 3975);
WIRE 16 -1 (-5550 3975)(-5550 4025);
WIRE 16 -1 (-5550 4025)(-5350 4025);
WIRE 16 -1 (-5550 4025)(-5550 4075);
WIRE 16 -1 (-5550 4075)(-5350 4075);
WIRE 16 -1 (-5550 4075)(-5550 4125);
WIRE 16 -1 (-5550 4125)(-5350 4125);
WIRE 16 -1 (-5550 4125)(-5550 4175);
WIRE 16 -1 (-5550 4175)(-5350 4175);
WIRE 16 -1 (-5550 4175)(-5550 4225);
WIRE 16 -1 (-5550 4225)(-5350 4225);
WIRE 16 -1 (-5550 4225)(-5550 4275);
WIRE 16 -1 (-5550 4275)(-5350 4275);
WIRE 16 -1 (-5550 4275)(-5550 4325);
WIRE 16 -1 (-5550 4325)(-5350 4325);
WIRE 16 -1 (-5550 4325)(-5550 4375);
WIRE 16 -1 (-5550 4375)(-5350 4375);
WIRE 16 -1 (-5550 4375)(-5550 4425);
WIRE 16 -1 (-5550 4425)(-5350 4425);
WIRE 16 -1 (-5550 4425)(-5550 4475);
WIRE 16 -1 (-5550 4475)(-5350 4475);
WIRE 16 -1 (-5550 4475)(-5550 4525);
WIRE 16 -1 (-5550 4525)(-5350 4525);
WIRE 16 -1 (-5550 4525)(-5550 4575);
WIRE 16 -1 (-5550 4575)(-5350 4575);
WIRE 16 -1 (-5550 4575)(-5550 4625);
WIRE 16 -1 (-5550 4625)(-5350 4625);
WIRE 16 -1 (-5550 4625)(-5550 4675);
WIRE 16 -1 (-5550 4675)(-5350 4675);
WIRE 16 -1 (-5550 4675)(-5550 4725);
WIRE 16 -1 (-5550 4725)(-5350 4725);
WIRE 16 -1 (-5550 4725)(-5550 4775);
WIRE 16 -1 (-5550 4775)(-5350 4775);
WIRE 16 -1 (-5550 4775)(-5550 4825);
WIRE 16 -1 (-5550 4825)(-5350 4825);
WIRE 16 -1 (-5550 4825)(-5550 4875);
WIRE 16 -1 (-5550 4875)(-5350 4875);
WIRE 16 -1 (-5550 4875)(-5550 4925);
WIRE 16 -1 (-5550 4925)(-5350 4925);
WIRE 16 -1 (-5550 4925)(-5550 4975);
WIRE 16 -1 (-5550 4975)(-5350 4975);
WIRE 16 -1 (-5550 4975)(-5550 5025);
WIRE 16 -1 (-5550 5025)(-5350 5025);
WIRE 16 -1 (-4150 5025)(-3950 5025);
WIRE 16 -1 (-3950 5025)(-3950 4975);
WIRE 16 -1 (-4150 4975)(-3950 4975);
WIRE 16 -1 (-3950 4975)(-3950 4925);
WIRE 16 -1 (-4150 4925)(-3950 4925);
WIRE 16 -1 (-3950 4925)(-3950 4875);
WIRE 16 -1 (-4150 4875)(-3950 4875);
WIRE 16 -1 (-3950 4875)(-3950 4825);
WIRE 16 -1 (-4150 4825)(-3950 4825);
WIRE 16 -1 (-3950 4825)(-3950 4775);
WIRE 16 -1 (-4150 4775)(-3950 4775);
WIRE 16 -1 (-3950 4775)(-3950 4725);
WIRE 16 -1 (-4150 4725)(-3950 4725);
WIRE 16 -1 (-3950 4725)(-3950 4675);
WIRE 16 -1 (-4150 4675)(-3950 4675);
DOT 1 (-3950 4725);
DOT 1 (-3950 4775);
DOT 1 (-3950 4825);
DOT 1 (-3950 4875);
DOT 1 (-3950 4925);
DOT 1 (-3950 4975);
DOT 1 (-3950 5025);
DOT 1 (-5550 4175);
DOT 1 (-5550 4225);
DOT 1 (-5550 4275);
DOT 1 (-5550 4875);
DOT 1 (-5550 4825);
DOT 1 (-5550 3875);
DOT 1 (-5550 3925);
DOT 1 (-5550 3975);
DOT 1 (-5550 4025);
DOT 1 (-5550 4075);
DOT 1 (-5550 4125);
DOT 1 (-5550 4325);
DOT 1 (-5550 4375);
DOT 1 (-5550 4425);
DOT 1 (-5550 4475);
DOT 1 (-5550 4525);
DOT 1 (-5550 4575);
DOT 1 (-5550 4625);
DOT 1 (-5550 4675);
DOT 1 (-5550 4725);
DOT 1 (-5550 4775);
DOT 1 (-5550 4925);
DOT 1 (-5550 4975);
QUIT
